(kicad_pcb
	(version 20260206)
	(generator "pcbnew")
	(generator_version "10.0")
	(general
		(thickness 1.6)
		(legacy_teardrops no)
	)
	(paper "A4")
	(title_block
		(title "Bryce Canyon_R.DPB_16317-1_OCP.brd")
		(comment 1 "Bryce Canyon / footprints 719-724 of 2099")
	)
	(layers
		(0 "F.Cu" signal "TOP")
		(4 "In1.Cu" signal "L2GND")
		(6 "In2.Cu" signal "L3")
		(8 "In3.Cu" signal "L4VCC")
		(10 "In4.Cu" signal "L5VCC")
		(12 "In5.Cu" signal "L6")
		(14 "In6.Cu" signal "L7GND")
		(2 "B.Cu" signal "BOTTOM")
		(9 "F.Adhes" user "F.Adhesive")
		(11 "B.Adhes" user "B.Adhesive")
		(13 "F.Paste" user "Package Geometry/Pastemask Top")
		(15 "B.Paste" user "Package Geometry/Pastemask Bottom")
		(5 "F.SilkS" user "Ref Des/Silkscreen Top")
		(7 "B.SilkS" user "Ref Des/Silkscreen Bottom")
		(1 "F.Mask" user "Board Geometry/Soldermask Top")
		(3 "B.Mask" user "Board Geometry/Soldermask Bottom")
		(17 "Dwgs.User" user "User.Drawings")
		(19 "Cmts.User" user "User.Comments")
		(21 "Eco1.User" user "User.Eco1")
		(23 "Eco2.User" user "User.Eco2")
		(25 "Edge.Cuts" user "Board Geometry/Outline")
		(27 "Margin" user)
		(31 "F.CrtYd" user "Package Geometry/Place Bound Top")
		(29 "B.CrtYd" user "Package Geometry/Place Bound Bottom")
		(35 "F.Fab" user "Ref Des/Assembly Top")
		(33 "B.Fab" user "Ref Des/Assembly Bottom")
	)
	(footprint ""
		(layer "F.Cu")
		(at 190.5 -32.131 90)
		(property "Reference" "C414"
			(at 0 0 90)
			(layer "F.SilkS")
			(hide yes)
			(effects
				(font
					(size 1.27 1.27)
				)
			)
		)
		(property "Value" "SCD01U50V2KX-1GP"
			(at 1.1811 -2.7051 90)
			(unlocked yes)
			(layer "F.Fab")
			(hide yes)
			(effects
				(font
					(size 1.016 1.016)
					(thickness 0.1524)
				)
			)
		)
		(property "Device Type" "C402H22"
			(at 1.1811 -4.2291 90)
			(unlocked yes)
			(layer "F.Fab")
			(hide yes)
			(effects
				(font
					(size 1.016 1.016)
					(thickness 0.1524)
				)
			)
		)
		(duplicate_pad_numbers_are_jumpers no)
		(fp_rect
			(start -0.4318 0.9525)
			(end 0.4318 -0.9525)
			(stroke
				(width 0)
				(type default)
			)
			(fill no)
			(layer "F.CrtYd")
		)
		(fp_rect
			(start -0.4318 0.9525)
			(end 0.4318 -0.9525)
			(stroke
				(width 0)
				(type default)
			)
			(fill no)
			(layer "F.Fab")
		)
		(pad "1" smd custom
			(at 0 -0.4445 90)
			(size 0.1524 0.1524)
			(layers "F.Cu" "F.Mask" "F.Paste")
			(net "HDD_PRSNT_29")
			(options
				(clearance outline)
				(anchor circle)
			)
			(primitives
				(gr_poly
					(pts
						(arc
							(start 0.3048 -0.2032)
							(mid 0.275042 -0.275042)
							(end 0.2032 -0.3048)
						)
						(arc
							(start -0.2032 -0.3048)
							(mid -0.275042 -0.275042)
							(end -0.3048 -0.2032)
						)
						(arc
							(start -0.3048 0.2032)
							(mid -0.275042 0.275042)
							(end -0.2032 0.3048)
						)
						(arc
							(start 0.2032 0.3048)
							(mid 0.275042 0.275042)
							(end 0.3048 0.2032)
						)
					)
					(width 0)
					(fill yes)
				)
			)
		)
		(pad "2" smd custom
			(at 0 0.4445 90)
			(size 0.1524 0.1524)
			(layers "F.Cu" "F.Mask" "F.Paste")
			(net "GND")
			(options
				(clearance outline)
				(anchor circle)
			)
			(primitives
				(gr_poly
					(pts
						(arc
							(start 0.3048 -0.2032)
							(mid 0.275042 -0.275042)
							(end 0.2032 -0.3048)
						)
						(arc
							(start -0.2032 -0.3048)
							(mid -0.275042 -0.275042)
							(end -0.3048 -0.2032)
						)
						(arc
							(start -0.3048 0.2032)
							(mid -0.275042 0.275042)
							(end -0.2032 0.3048)
						)
						(arc
							(start 0.2032 0.3048)
							(mid 0.275042 0.275042)
							(end 0.3048 0.2032)
						)
					)
					(width 0)
					(fill yes)
				)
			)
		)
	)
	(footprint ""
		(layer "F.Cu")
		(at 207.3402 -197.231 -90)
		(property "Reference" "R28"
			(at 0 0 270)
			(layer "F.SilkS")
			(hide yes)
			(effects
				(font
					(size 1.27 1.27)
				)
			)
		)
		(property "Value" "4K7R2F-GP"
			(at 0.064008 -3.993896 270)
			(unlocked yes)
			(layer "F.Fab")
			(hide yes)
			(effects
				(font
					(size 1.016 1.016)
					(thickness 0.1524)
				)
			)
		)
		(property "Device Type" "R402H16"
			(at 0.064008 -5.517896 270)
			(unlocked yes)
			(layer "F.Fab")
			(hide yes)
			(effects
				(font
					(size 1.016 1.016)
					(thickness 0.1524)
				)
			)
		)
		(duplicate_pad_numbers_are_jumpers no)
		(fp_line
			(start -0.508 -0.9398)
			(end -0.508 0.9398)
			(stroke
				(width 0.1524)
				(type default)
			)
			(layer "F.SilkS")
		)
		(fp_line
			(start 0.508 -0.9398)
			(end -0.508 -0.9398)
			(stroke
				(width 0.1524)
				(type default)
			)
			(layer "F.SilkS")
		)
		(fp_rect
			(start -0.508 0.9398)
			(end 0.508 -0.9398)
			(stroke
				(width 0)
				(type default)
			)
			(fill no)
			(layer "F.CrtYd")
		)
		(fp_rect
			(start -0.508 0.9398)
			(end 0.508 -0.9398)
			(stroke
				(width 0)
				(type default)
			)
			(fill no)
			(layer "F.Fab")
		)
		(pad "1" smd custom
			(at 0 -0.4445 270)
			(size 0.1397 0.1397)
			(layers "F.Cu" "F.Mask" "F.Paste")
			(net "IO_EXP2_HDD_FAULT_A1")
			(options
				(clearance outline)
				(anchor circle)
			)
			(primitives
				(gr_poly
					(pts
						(arc
							(start -0.1778 -0.2794)
							(mid -0.249642 -0.249642)
							(end -0.2794 -0.1778)
						)
						(arc
							(start -0.2794 0.1778)
							(mid -0.249642 0.249642)
							(end -0.1778 0.2794)
						)
						(arc
							(start 0.1778 0.2794)
							(mid 0.249642 0.249642)
							(end 0.2794 0.1778)
						)
						(arc
							(start 0.2794 -0.1778)
							(mid 0.249642 -0.249642)
							(end 0.1778 -0.2794)
						)
					)
					(width 0)
					(fill yes)
				)
			)
		)
		(pad "2" smd custom
			(at 0 0.4445 270)
			(size 0.1397 0.1397)
			(layers "F.Cu" "F.Mask" "F.Paste")
			(net "GND")
			(options
				(clearance outline)
				(anchor circle)
			)
			(primitives
				(gr_poly
					(pts
						(arc
							(start -0.1778 -0.2794)
							(mid -0.249642 -0.249642)
							(end -0.2794 -0.1778)
						)
						(arc
							(start -0.2794 0.1778)
							(mid -0.249642 0.249642)
							(end -0.1778 0.2794)
						)
						(arc
							(start 0.1778 0.2794)
							(mid 0.249642 0.249642)
							(end 0.2794 0.1778)
						)
						(arc
							(start 0.2794 -0.1778)
							(mid 0.249642 -0.249642)
							(end 0.1778 -0.2794)
						)
					)
					(width 0)
					(fill yes)
				)
			)
		)
	)
	(footprint ""
		(layer "F.Cu")
		(at 83.82 -141.224 180)
		(property "Reference" "Q57"
			(at 0 0 180)
			(layer "F.SilkS")
			(hide yes)
			(effects
				(font
					(size 1.27 1.27)
				)
			)
		)
		(property "Value" "AO4406AL-GP"
			(at -3.707384 -1.5367 180)
			(unlocked yes)
			(layer "F.Fab")
			(hide yes)
			(effects
				(font
					(size 1.016 1.016)
					(thickness 0.1524)
				)
			)
		)
		(property "Device Type" "SOIC8H69"
			(at -3.707384 -3.0607 180)
			(unlocked yes)
			(layer "F.Fab")
			(hide yes)
			(effects
				(font
					(size 1.016 1.016)
					(thickness 0.1524)
				)
			)
		)
		(duplicate_pad_numbers_are_jumpers no)
		(fp_line
			(start 2.1336 1.4224)
			(end 2.1336 -1.4224)
			(stroke
				(width 0.1524)
				(type default)
			)
			(layer "F.SilkS")
		)
		(fp_line
			(start 2.1336 -1.4224)
			(end -2.7432 -1.4224)
			(stroke
				(width 0.1524)
				(type default)
			)
			(layer "F.SilkS")
		)
		(fp_line
			(start -2.1844 -0.0508)
			(end -2.7178 0.508)
			(stroke
				(width 0.1524)
				(type default)
			)
			(layer "F.SilkS")
		)
		(fp_line
			(start -2.6289 3.4417)
			(end -2.6289 1.4732)
			(stroke
				(width 0.381)
				(type default)
			)
			(layer "F.SilkS")
		)
		(fp_line
			(start -2.7178 -0.508)
			(end -2.1844 -0.0508)
			(stroke
				(width 0.1524)
				(type default)
			)
			(layer "F.SilkS")
		)
		(fp_line
			(start -2.7432 1.4224)
			(end 2.1336 1.4224)
			(stroke
				(width 0.1524)
				(type default)
			)
			(layer "F.SilkS")
		)
		(fp_line
			(start -2.7432 1.4224)
			(end -2.6416 1.4224)
			(stroke
				(width 0.1524)
				(type default)
			)
			(layer "F.SilkS")
		)
		(fp_line
			(start -2.7432 -1.4224)
			(end -2.7432 1.4224)
			(stroke
				(width 0.1524)
				(type default)
			)
			(layer "F.SilkS")
		)
		(fp_poly
			(pts
				(xy -2.2098 -1.4224) (xy -2.2098 1.4224) (xy 2.2098 1.4224) (xy 2.2098 -1.4224)
			)
			(stroke
				(width 0)
				(type default)
			)
			(fill yes)
			(layer "F.SilkS")
		)
		(fp_rect
			(start -2.450084 2.999994)
			(end 2.450084 -2.999994)
			(stroke
				(width 0)
				(type default)
			)
			(fill no)
			(layer "F.CrtYd")
		)
		(fp_poly
			(pts
				(xy -2.8194 3.6322) (xy -2.8194 -3.6322) (xy 2.8194 -3.6322) (xy 2.8194 1.18364) (xy 2.450084 1.18364)
				(xy 2.450084 -2.999994) (xy -2.450084 -2.999994) (xy -2.450084 2.999994) (xy 2.450084 2.999994)
				(xy 2.450084 1.18618) (xy 2.8194 1.18618) (xy 2.8194 3.6322)
			)
			(stroke
				(width 0)
				(type default)
			)
			(fill no)
			(layer "F.CrtYd")
		)
		(fp_rect
			(start -2.8194 3.6322)
			(end 2.8194 -3.6322)
			(stroke
				(width 0)
				(type default)
			)
			(fill no)
			(layer "F.Fab")
		)
		(pad "1" smd rect
			(at -1.905 2.54 180)
			(size 0.635 1.651)
			(layers "F.Cu" "F.Mask" "F.Paste")
			(net "P5V_HDD14")
		)
		(pad "2" smd rect
			(at -0.635 2.54 180)
			(size 0.635 1.651)
			(layers "F.Cu" "F.Mask" "F.Paste")
			(net "P5V_HDD14")
		)
		(pad "3" smd rect
			(at 0.635 2.54 180)
			(size 0.635 1.651)
			(layers "F.Cu" "F.Mask" "F.Paste")
			(net "P5V_HDD14")
		)
		(pad "4" smd rect
			(at 1.905 2.54 180)
			(size 0.635 1.651)
			(layers "F.Cu" "F.Mask" "F.Paste")
			(net "SW_HDD_P14")
		)
		(pad "5" smd rect
			(at 1.905 -2.54 180)
			(size 0.635 1.651)
			(layers "F.Cu" "F.Mask" "F.Paste")
			(net "P5V_B_1")
		)
		(pad "6" smd rect
			(at 0.635 -2.54 180)
			(size 0.635 1.651)
			(layers "F.Cu" "F.Mask" "F.Paste")
			(net "P5V_B_1")
		)
		(pad "7" smd rect
			(at -0.635 -2.54 180)
			(size 0.635 1.651)
			(layers "F.Cu" "F.Mask" "F.Paste")
			(net "P5V_B_1")
		)
		(pad "8" smd rect
			(at -1.905 -2.54 180)
			(size 0.635 1.651)
			(layers "F.Cu" "F.Mask" "F.Paste")
			(net "P5V_B_1")
		)
	)
	(footprint ""
		(layer "F.Cu")
		(at 343.993978 -102.413562 -90)
		(property "Reference" "R470"
			(at 0 0 270)
			(layer "F.SilkS")
			(hide yes)
			(effects
				(font
					(size 1.27 1.27)
				)
			)
		)
		(property "Value" "4K7R2F-GP"
			(at 0.064008 -3.993896 270)
			(unlocked yes)
			(layer "F.Fab")
			(hide yes)
			(effects
				(font
					(size 1.016 1.016)
					(thickness 0.1524)
				)
			)
		)
		(property "Device Type" "R402H16"
			(at 0.064008 -5.517896 270)
			(unlocked yes)
			(layer "F.Fab")
			(hide yes)
			(effects
				(font
					(size 1.016 1.016)
					(thickness 0.1524)
				)
			)
		)
		(duplicate_pad_numbers_are_jumpers no)
		(fp_line
			(start -0.508 -0.9398)
			(end -0.508 0.9398)
			(stroke
				(width 0.1524)
				(type default)
			)
			(layer "F.SilkS")
		)
		(fp_line
			(start 0.508 -0.9398)
			(end -0.508 -0.9398)
			(stroke
				(width 0.1524)
				(type default)
			)
			(layer "F.SilkS")
		)
		(fp_rect
			(start -0.508 0.9398)
			(end 0.508 -0.9398)
			(stroke
				(width 0)
				(type default)
			)
			(fill no)
			(layer "F.CrtYd")
		)
		(fp_rect
			(start -0.508 0.9398)
			(end 0.508 -0.9398)
			(stroke
				(width 0)
				(type default)
			)
			(fill no)
			(layer "F.Fab")
		)
		(pad "1" smd custom
			(at 0 -0.4445 270)
			(size 0.1397 0.1397)
			(layers "F.Cu" "F.Mask" "F.Paste")
			(net "DRIVE_B_19_FLT_LED")
			(options
				(clearance outline)
				(anchor circle)
			)
			(primitives
				(gr_poly
					(pts
						(arc
							(start -0.1778 -0.2794)
							(mid -0.249642 -0.249642)
							(end -0.2794 -0.1778)
						)
						(arc
							(start -0.2794 0.1778)
							(mid -0.249642 0.249642)
							(end -0.1778 0.2794)
						)
						(arc
							(start 0.1778 0.2794)
							(mid 0.249642 0.249642)
							(end 0.2794 0.1778)
						)
						(arc
							(start 0.2794 -0.1778)
							(mid 0.249642 -0.249642)
							(end 0.1778 -0.2794)
						)
					)
					(width 0)
					(fill yes)
				)
			)
		)
		(pad "2" smd custom
			(at 0 0.4445 270)
			(size 0.1397 0.1397)
			(layers "F.Cu" "F.Mask" "F.Paste")
			(net "GND")
			(options
				(clearance outline)
				(anchor circle)
			)
			(primitives
				(gr_poly
					(pts
						(arc
							(start -0.1778 -0.2794)
							(mid -0.249642 -0.249642)
							(end -0.2794 -0.1778)
						)
						(arc
							(start -0.2794 0.1778)
							(mid -0.249642 0.249642)
							(end -0.1778 0.2794)
						)
						(arc
							(start 0.1778 0.2794)
							(mid 0.249642 0.249642)
							(end 0.2794 0.1778)
						)
						(arc
							(start 0.2794 -0.1778)
							(mid 0.249642 -0.249642)
							(end 0.1778 -0.2794)
						)
					)
					(width 0)
					(fill yes)
				)
			)
		)
	)
	(footprint ""
		(layer "F.Cu")
		(at 434.939186 -116.257578 -90)
		(property "Reference" "R1169"
			(at 0 0 270)
			(layer "F.SilkS")
			(hide yes)
			(effects
				(font
					(size 1.27 1.27)
				)
			)
		)
		(property "Value" "309KR2F-GP"
			(at 0.064008 -3.993896 270)
			(unlocked yes)
			(layer "F.Fab")
			(hide yes)
			(effects
				(font
					(size 1.016 1.016)
					(thickness 0.1524)
				)
			)
		)
		(property "Device Type" "R402H16"
			(at 0.064008 -5.517896 270)
			(unlocked yes)
			(layer "F.Fab")
			(hide yes)
			(effects
				(font
					(size 1.016 1.016)
					(thickness 0.1524)
				)
			)
		)
		(duplicate_pad_numbers_are_jumpers no)
		(fp_line
			(start -0.508 -0.9398)
			(end -0.508 0.9398)
			(stroke
				(width 0.1524)
				(type default)
			)
			(layer "F.SilkS")
		)
		(fp_line
			(start 0.508 -0.9398)
			(end -0.508 -0.9398)
			(stroke
				(width 0.1524)
				(type default)
			)
			(layer "F.SilkS")
		)
		(fp_rect
			(start -0.508 0.9398)
			(end 0.508 -0.9398)
			(stroke
				(width 0)
				(type default)
			)
			(fill no)
			(layer "F.CrtYd")
		)
		(fp_rect
			(start -0.508 0.9398)
			(end 0.508 -0.9398)
			(stroke
				(width 0)
				(type default)
			)
			(fill no)
			(layer "F.Fab")
		)
		(pad "1" smd custom
			(at 0 -0.4445 270)
			(size 0.1397 0.1397)
			(layers "F.Cu" "F.Mask" "F.Paste")
			(net "P5V_B_4_RF")
			(options
				(clearance outline)
				(anchor circle)
			)
			(primitives
				(gr_poly
					(pts
						(arc
							(start -0.1778 -0.2794)
							(mid -0.249642 -0.249642)
							(end -0.2794 -0.1778)
						)
						(arc
							(start -0.2794 0.1778)
							(mid -0.249642 0.249642)
							(end -0.1778 0.2794)
						)
						(arc
							(start 0.1778 0.2794)
							(mid 0.249642 0.249642)
							(end 0.2794 0.1778)
						)
						(arc
							(start 0.2794 -0.1778)
							(mid 0.249642 -0.249642)
							(end 0.1778 -0.2794)
						)
					)
					(width 0)
					(fill yes)
				)
			)
		)
		(pad "2" smd custom
			(at 0 0.4445 270)
			(size 0.1397 0.1397)
			(layers "F.Cu" "F.Mask" "F.Paste")
			(net "P5V_B_4_VREG")
			(options
				(clearance outline)
				(anchor circle)
			)
			(primitives
				(gr_poly
					(pts
						(arc
							(start -0.1778 -0.2794)
							(mid -0.249642 -0.249642)
							(end -0.2794 -0.1778)
						)
						(arc
							(start -0.2794 0.1778)
							(mid -0.249642 0.249642)
							(end -0.1778 0.2794)
						)
						(arc
							(start 0.1778 0.2794)
							(mid 0.249642 0.249642)
							(end 0.2794 0.1778)
						)
						(arc
							(start 0.2794 -0.1778)
							(mid 0.249642 -0.249642)
							(end 0.1778 -0.2794)
						)
					)
					(width 0)
					(fill yes)
				)
			)
		)
	)
	(footprint ""
		(layer "F.Cu")
		(at 281.559 -340.18601 180)
		(property "Reference" "U48"
			(at 0 0 180)
			(layer "F.SilkS")
			(hide yes)
			(effects
				(font
					(size 1.27 1.27)
				)
			)
		)
		(property "Value" "RT9077-33GJ5-GP"
			(at 0 -5.1308 180)
			(unlocked yes)
			(layer "F.Fab")
			(hide yes)
			(effects
				(font
					(size 1.016 1.016)
					(thickness 0.1524)
				)
			)
		)
		(property "Device Type" "SOT-23-5H40"
			(at 0 -6.7564 180)
			(unlocked yes)
			(layer "F.Fab")
			(hide yes)
			(effects
				(font
					(size 1.016 1.016)
					(thickness 0.1524)
				)
			)
		)
		(duplicate_pad_numbers_are_jumpers no)
		(fp_line
			(start 1.778 2.286)
			(end 1.778 -2.286)
			(stroke
				(width 0.1524)
				(type default)
			)
			(layer "F.SilkS")
		)
		(fp_line
			(start 1.778 -2.286)
			(end -1.778 -2.286)
			(stroke
				(width 0.1524)
				(type default)
			)
			(layer "F.SilkS")
		)
		(fp_line
			(start -0.254 2.286)
			(end 1.778 2.286)
			(stroke
				(width 0.1524)
				(type default)
			)
			(layer "F.SilkS")
		)
		(fp_line
			(start -0.7112 2.2352)
			(end -1.7272 2.2352)
			(stroke
				(width 0.3302)
				(type default)
			)
			(layer "F.SilkS")
		)
		(fp_line
			(start -1.7272 2.2352)
			(end -1.7272 0.762)
			(stroke
				(width 0.3302)
				(type default)
			)
			(layer "F.SilkS")
		)
		(fp_line
			(start -1.778 2.286)
			(end 1.778 2.286)
			(stroke
				(width 0.1524)
				(type default)
			)
			(layer "F.SilkS")
		)
		(fp_line
			(start -1.778 2.286)
			(end -0.254 2.286)
			(stroke
				(width 0.1524)
				(type default)
			)
			(layer "F.SilkS")
		)
		(fp_line
			(start -1.778 -2.286)
			(end -1.778 2.286)
			(stroke
				(width 0.1524)
				(type default)
			)
			(layer "F.SilkS")
		)
		(fp_poly
			(pts
				(xy -0.9652 2.4384) (xy -1.3208 2.794) (xy -0.6096 2.794)
			)
			(stroke
				(width 0)
				(type default)
			)
			(fill yes)
			(layer "F.SilkS")
		)
		(fp_rect
			(start -1.778 2.286)
			(end 1.778 -2.286)
			(stroke
				(width 0)
				(type default)
			)
			(fill no)
			(layer "F.CrtYd")
		)
		(fp_rect
			(start -1.778 2.286)
			(end 1.778 -2.286)
			(stroke
				(width 0)
				(type default)
			)
			(fill no)
			(layer "F.Fab")
		)
		(pad "1" smd rect
			(at -0.94996 1.143 180)
			(size 0.508 1.524)
			(layers "F.Cu" "F.Mask" "F.Paste")
			(net "P12V_IN")
		)
		(pad "2" smd rect
			(at 0 1.143 180)
			(size 0.508 1.524)
			(layers "F.Cu" "F.Mask" "F.Paste")
			(net "GND")
		)
		(pad "3" smd rect
			(at 0.94996 1.143 180)
			(size 0.508 1.524)
			(layers "F.Cu" "F.Mask" "F.Paste")
			(net "P3V3_IN_EN")
		)
		(pad "4" smd rect
			(at 0.94996 -1.143 180)
			(size 0.508 1.524)
			(layers "F.Cu" "F.Mask" "F.Paste")
			(net "Net_22")
		)
		(pad "5" smd rect
			(at -0.94996 -1.143 180)
			(size 0.508 1.524)
			(layers "F.Cu" "F.Mask" "F.Paste")
			(net "P3V3_IN")
		)
	)
)
